# T6G (Grand Teton) — schematic netlist excerpt (pin names and nets, part order shuffled) for the footprints in the layout excerpt that follows; sources: Cadence DE-HDL packaged netlist, KiCad conversion of 04192023_DAF0TMB3IC0_F0TG_MB_C_brd_V02_OCP.brd

R640  Q_RES  51.1 1% EMPTY  pkg 0201LF  page 342 : A = CLK_100M_RETIMER_CPU1_P2_DP ; B = GND
PC175_9  Q_CAP  0.1UF 25V 10% X7R  pkg 0402  page 206 : A = PVDDCR_CPU1_P0_VCCS ; B = GND
C39  Q_CAP  1UF 25V 10% X6S  pkg C0402  page 140 : A = P3V3_OCP_VCC_2 ; B = GND

(kicad_pcb
	(version 20260206)
	(generator "pcbnew")
	(generator_version "10.0")
	(general
		(thickness 1.6)
		(legacy_teardrops no)
	)
	(paper "A4")
	(title_block
		(title "04192023_DAF0TMB3IC0_F0TG_MB_C_brd_V02_OCP.brd")
		(comment 1 "Grand Teton / footprints 4684-4686 of 8354")
	)
	(layers
		(0 "F.Cu" signal "TOP")
		(4 "In1.Cu" signal "GND")
		(6 "In2.Cu" signal "IN1")
		(8 "In3.Cu" signal "GND1")
		(10 "In4.Cu" signal "IN2")
		(12 "In5.Cu" signal "GND2")
		(14 "In6.Cu" signal "IN3")
		(16 "In7.Cu" signal "GND3")
		(18 "In8.Cu" signal "VCC")
		(20 "In9.Cu" signal "VCC1")
		(22 "In10.Cu" signal "GND4")
		(24 "In11.Cu" signal "IN4")
		(26 "In12.Cu" signal "GND5")
		(28 "In13.Cu" signal "IN5")
		(30 "In14.Cu" signal "GND6")
		(32 "In15.Cu" signal "IN6")
		(34 "In16.Cu" signal "GND7")
		(2 "B.Cu" signal "BOTTOM")
		(9 "F.Adhes" user "F.Adhesive")
		(11 "B.Adhes" user "B.Adhesive")
		(13 "F.Paste" user "Package Geometry/Pastemask Top")
		(15 "B.Paste" user "Package Geometry/Pastemask Bottom")
		(5 "F.SilkS" user "Ref Des/Silkscreen Top")
		(7 "B.SilkS" user "Ref Des/Silkscreen Bottom")
		(1 "F.Mask" user "Board Geometry/Soldermask Top")
		(3 "B.Mask" user "Board Geometry/Soldermask Bottom")
		(17 "Dwgs.User" user "User.Drawings")
		(19 "Cmts.User" user "User.Comments")
		(21 "Eco1.User" user "User.Eco1")
		(23 "Eco2.User" user "User.Eco2")
		(25 "Edge.Cuts" user "Board Geometry/Outline")
		(27 "Margin" user)
		(31 "F.CrtYd" user "Package Geometry/Place Bound Top")
		(29 "B.CrtYd" user "Package Geometry/Place Bound Bottom")
		(35 "F.Fab" user "Ref Des/Assembly Top")
		(33 "B.Fab" user "Ref Des/Assembly Bottom")
	)
	(footprint ""
		(layer "F.Cu")
		(at 281.008582 -351.573846 90)
		(property "Reference" "PC175_9"
			(at 0 0 90)
			(layer "F.SilkS")
			(hide yes)
			(effects
				(font
					(size 1.27 1.27)
				)
			)
		)
		(property "Value" ""
			(at 0 0 90)
			(layer "F.Fab")
			(effects
				(font
					(size 1.27 1.27)
				)
			)
		)
		(duplicate_pad_numbers_are_jumpers no)
		(fp_line
			(start 0.7874 -0.4064)
			(end 0.7874 0.4064)
			(stroke
				(width 0.1524)
				(type default)
			)
			(layer "F.SilkS")
		)
		(fp_line
			(start -0.7874 -0.4064)
			(end 0.7874 -0.4064)
			(stroke
				(width 0.1524)
				(type default)
			)
			(layer "F.SilkS")
		)
		(fp_line
			(start 0.7874 0.4064)
			(end -0.7874 0.4064)
			(stroke
				(width 0.1524)
				(type default)
			)
			(layer "F.SilkS")
		)
		(fp_line
			(start -0.7874 0.4064)
			(end -0.7874 -0.4064)
			(stroke
				(width 0.1524)
				(type default)
			)
			(layer "F.SilkS")
		)
		(fp_line
			(start -0.12065 -0.305054)
			(end -0.12065 -0.2794)
			(stroke
				(width 0.1)
				(type default)
			)
			(layer "F.Fab")
		)
		(fp_line
			(start -0.67945 -0.305054)
			(end -0.12065 -0.305054)
			(stroke
				(width 0.1)
				(type default)
			)
			(layer "F.Fab")
		)
		(fp_line
			(start 0.67945 -0.3048)
			(end 0.67945 0.3048)
			(stroke
				(width 0.1)
				(type default)
			)
			(layer "F.Fab")
		)
		(fp_line
			(start 0.12065 -0.3048)
			(end 0.67945 -0.3048)
			(stroke
				(width 0.1)
				(type default)
			)
			(layer "F.Fab")
		)
		(fp_line
			(start 0.12065 -0.2794)
			(end 0.12065 -0.3048)
			(stroke
				(width 0.1)
				(type default)
			)
			(layer "F.Fab")
		)
		(fp_line
			(start -0.12065 -0.2794)
			(end 0.12065 -0.2794)
			(stroke
				(width 0.1)
				(type default)
			)
			(layer "F.Fab")
		)
		(fp_line
			(start 0.120396 0.2794)
			(end -0.12065 0.2794)
			(stroke
				(width 0.1)
				(type default)
			)
			(layer "F.Fab")
		)
		(fp_line
			(start -0.12065 0.2794)
			(end -0.12065 0.3048)
			(stroke
				(width 0.1)
				(type default)
			)
			(layer "F.Fab")
		)
		(fp_line
			(start 0.67945 0.3048)
			(end 0.120396 0.3048)
			(stroke
				(width 0.1)
				(type default)
			)
			(layer "F.Fab")
		)
		(fp_line
			(start 0.120396 0.3048)
			(end 0.120396 0.2794)
			(stroke
				(width 0.1)
				(type default)
			)
			(layer "F.Fab")
		)
		(fp_line
			(start -0.12065 0.3048)
			(end -0.67945 0.3048)
			(stroke
				(width 0.1)
				(type default)
			)
			(layer "F.Fab")
		)
		(fp_line
			(start -0.67945 0.3048)
			(end -0.67945 -0.305054)
			(stroke
				(width 0.1)
				(type default)
			)
			(layer "F.Fab")
		)
		(pad "1" smd circle
			(at -0.40005 0 90)
			(size 0 0)
			(layers "F.Cu" "F.Mask" "F.Paste")
			(net "PVDDCR_CPU1_P0_VCCS")
		)
		(pad "2" smd circle
			(at 0.40005 0 90)
			(size 0 0)
			(layers "F.Cu" "F.Mask" "F.Paste")
			(net "GND")
		)
	)
	(footprint ""
		(layer "F.Cu")
		(at 93.29801 -55.717694)
		(property "Reference" "C39"
			(at 0 0 0)
			(layer "F.SilkS")
			(hide yes)
			(effects
				(font
					(size 1.27 1.27)
				)
			)
		)
		(property "Value" ""
			(at 0 0 0)
			(layer "F.Fab")
			(effects
				(font
					(size 1.27 1.27)
				)
			)
		)
		(duplicate_pad_numbers_are_jumpers no)
		(fp_line
			(start -0.7874 -0.4064)
			(end 0.7874 -0.4064)
			(stroke
				(width 0.1524)
				(type default)
			)
			(layer "F.SilkS")
		)
		(fp_line
			(start -0.7874 0.4064)
			(end -0.7874 -0.4064)
			(stroke
				(width 0.1524)
				(type default)
			)
			(layer "F.SilkS")
		)
		(fp_line
			(start 0.7874 -0.4064)
			(end 0.7874 0.4064)
			(stroke
				(width 0.1524)
				(type default)
			)
			(layer "F.SilkS")
		)
		(fp_line
			(start 0.7874 0.4064)
			(end -0.7874 0.4064)
			(stroke
				(width 0.1524)
				(type default)
			)
			(layer "F.SilkS")
		)
		(fp_line
			(start -0.67945 -0.305054)
			(end -0.12065 -0.305054)
			(stroke
				(width 0.1)
				(type default)
			)
			(layer "F.Fab")
		)
		(fp_line
			(start -0.67945 0.3048)
			(end -0.67945 -0.305054)
			(stroke
				(width 0.1)
				(type default)
			)
			(layer "F.Fab")
		)
		(fp_line
			(start -0.12065 -0.305054)
			(end -0.12065 -0.2794)
			(stroke
				(width 0.1)
				(type default)
			)
			(layer "F.Fab")
		)
		(fp_line
			(start -0.12065 -0.2794)
			(end 0.12065 -0.2794)
			(stroke
				(width 0.1)
				(type default)
			)
			(layer "F.Fab")
		)
		(fp_line
			(start -0.12065 0.2794)
			(end -0.12065 0.3048)
			(stroke
				(width 0.1)
				(type default)
			)
			(layer "F.Fab")
		)
		(fp_line
			(start -0.12065 0.3048)
			(end -0.67945 0.3048)
			(stroke
				(width 0.1)
				(type default)
			)
			(layer "F.Fab")
		)
		(fp_line
			(start 0.120396 0.2794)
			(end -0.12065 0.2794)
			(stroke
				(width 0.1)
				(type default)
			)
			(layer "F.Fab")
		)
		(fp_line
			(start 0.120396 0.3048)
			(end 0.120396 0.2794)
			(stroke
				(width 0.1)
				(type default)
			)
			(layer "F.Fab")
		)
		(fp_line
			(start 0.12065 -0.3048)
			(end 0.67945 -0.3048)
			(stroke
				(width 0.1)
				(type default)
			)
			(layer "F.Fab")
		)
		(fp_line
			(start 0.12065 -0.2794)
			(end 0.12065 -0.3048)
			(stroke
				(width 0.1)
				(type default)
			)
			(layer "F.Fab")
		)
		(fp_line
			(start 0.67945 -0.3048)
			(end 0.67945 0.3048)
			(stroke
				(width 0.1)
				(type default)
			)
			(layer "F.Fab")
		)
		(fp_line
			(start 0.67945 0.3048)
			(end 0.120396 0.3048)
			(stroke
				(width 0.1)
				(type default)
			)
			(layer "F.Fab")
		)
		(pad "1" smd circle
			(at -0.40005 0)
			(size 0 0)
			(layers "F.Cu" "F.Mask" "F.Paste")
			(net "P3V3_OCP_VCC_2")
		)
		(pad "2" smd circle
			(at 0.40005 0)
			(size 0 0)
			(layers "F.Cu" "F.Mask" "F.Paste")
			(net "GND")
		)
	)
	(footprint ""
		(layer "F.Cu")
		(at 143.171672 -388.030974 90)
		(property "Reference" "R640"
			(at 0 0 90)
			(layer "F.SilkS")
			(hide yes)
			(effects
				(font
					(size 1.27 1.27)
				)
			)
		)
		(property "Value" ""
			(at 0 0 90)
			(layer "F.Fab")
			(effects
				(font
					(size 1.27 1.27)
				)
			)
		)
		(duplicate_pad_numbers_are_jumpers no)
		(fp_line
			(start 0.32512 -0.175006)
			(end 0.32512 0.175006)
			(stroke
				(width 0.1)
				(type default)
			)
			(layer "F.Fab")
		)
		(fp_line
			(start -0.32512 -0.175006)
			(end 0.32512 -0.175006)
			(stroke
				(width 0.1)
				(type default)
			)
			(layer "F.Fab")
		)
		(fp_line
			(start 0.32512 0.175006)
			(end -0.32512 0.175006)
			(stroke
				(width 0.1)
				(type default)
			)
			(layer "F.Fab")
		)
		(fp_line
			(start -0.32512 0.175006)
			(end -0.32512 -0.175006)
			(stroke
				(width 0.1)
				(type default)
			)
			(layer "F.Fab")
		)
		(pad "1" smd rect
			(at -0.2667 0 90)
			(size 0.3048 0.381)
			(layers "F.Cu" "F.Mask" "F.Paste")
			(net "CLK_100M_RETIMER_CPU1_P2_DP")
		)
		(pad "2" smd rect
			(at 0.2667 0 270)
			(size 0.3048 0.381)
			(layers "F.Cu" "F.Mask" "F.Paste")
			(net "GND")
		)
	)
)
